# T6G (Grand Teton) — schematic netlist excerpt (pin names and nets, part order shuffled) for the footprints in the layout excerpt that follows; sources: Cadence DE-HDL packaged netlist, KiCad conversion of 04192023_DAF0TMB3IC0_F0TG_MB_C_brd_V02_OCP.brd

R179  Q_RES  33 5% CHIP  pkg 0402LF  page 82 : A = FM_CPU0_PROCHOT_R_N ; B = CPU0_PROCHOT_N
R130  Q_RES  10K 5% EMPTY  pkg 0402LF  page 151 : A = UART_VCC_J8 ; B = P5V_AUX
R1027  Q_RES  4.7K 5% EMPTY  pkg 0201LF  page 287 : A = P1V8_CPU0_RT_1D ; B = GPIO2_RT_CPU0_P1

(kicad_pcb
	(version 20260206)
	(generator "pcbnew")
	(generator_version "10.0")
	(general
		(thickness 1.6)
		(legacy_teardrops no)
	)
	(paper "A4")
	(title_block
		(title "04192023_DAF0TMB3IC0_F0TG_MB_C_brd_V02_OCP.brd")
		(comment 1 "Grand Teton / footprints 2810-2812 of 8354")
	)
	(layers
		(0 "F.Cu" signal "TOP")
		(4 "In1.Cu" signal "GND")
		(6 "In2.Cu" signal "IN1")
		(8 "In3.Cu" signal "GND1")
		(10 "In4.Cu" signal "IN2")
		(12 "In5.Cu" signal "GND2")
		(14 "In6.Cu" signal "IN3")
		(16 "In7.Cu" signal "GND3")
		(18 "In8.Cu" signal "VCC")
		(20 "In9.Cu" signal "VCC1")
		(22 "In10.Cu" signal "GND4")
		(24 "In11.Cu" signal "IN4")
		(26 "In12.Cu" signal "GND5")
		(28 "In13.Cu" signal "IN5")
		(30 "In14.Cu" signal "GND6")
		(32 "In15.Cu" signal "IN6")
		(34 "In16.Cu" signal "GND7")
		(2 "B.Cu" signal "BOTTOM")
		(9 "F.Adhes" user "F.Adhesive")
		(11 "B.Adhes" user "B.Adhesive")
		(13 "F.Paste" user "Package Geometry/Pastemask Top")
		(15 "B.Paste" user "Package Geometry/Pastemask Bottom")
		(5 "F.SilkS" user "Ref Des/Silkscreen Top")
		(7 "B.SilkS" user "Ref Des/Silkscreen Bottom")
		(1 "F.Mask" user "Board Geometry/Soldermask Top")
		(3 "B.Mask" user "Board Geometry/Soldermask Bottom")
		(17 "Dwgs.User" user "User.Drawings")
		(19 "Cmts.User" user "User.Comments")
		(21 "Eco1.User" user "User.Eco1")
		(23 "Eco2.User" user "User.Eco2")
		(25 "Edge.Cuts" user "Board Geometry/Outline")
		(27 "Margin" user)
		(31 "F.CrtYd" user "Package Geometry/Place Bound Top")
		(29 "B.CrtYd" user "Package Geometry/Place Bound Bottom")
		(35 "F.Fab" user "Ref Des/Assembly Top")
		(33 "B.Fab" user "Ref Des/Assembly Bottom")
	)
	(footprint ""
		(layer "F.Cu")
		(at 181.9402 -96.103948 -90)
		(property "Reference" "R179"
			(at 0 0 270)
			(layer "F.SilkS")
			(hide yes)
			(effects
				(font
					(size 1.27 1.27)
				)
			)
		)
		(property "Value" ""
			(at 0 0 270)
			(layer "F.Fab")
			(effects
				(font
					(size 1.27 1.27)
				)
			)
		)
		(duplicate_pad_numbers_are_jumpers no)
		(fp_line
			(start -0.7874 0.4064)
			(end -0.7874 -0.4064)
			(stroke
				(width 0.1524)
				(type default)
			)
			(layer "F.SilkS")
		)
		(fp_line
			(start 0.7874 0.4064)
			(end -0.7874 0.4064)
			(stroke
				(width 0.1524)
				(type default)
			)
			(layer "F.SilkS")
		)
		(fp_line
			(start -0.7874 -0.4064)
			(end 0.7874 -0.4064)
			(stroke
				(width 0.1524)
				(type default)
			)
			(layer "F.SilkS")
		)
		(fp_line
			(start 0.7874 -0.4064)
			(end 0.7874 0.4064)
			(stroke
				(width 0.1524)
				(type default)
			)
			(layer "F.SilkS")
		)
		(fp_line
			(start -0.67945 0.3048)
			(end -0.67945 -0.305054)
			(stroke
				(width 0.1)
				(type default)
			)
			(layer "F.Fab")
		)
		(fp_line
			(start -0.12065 0.3048)
			(end -0.67945 0.3048)
			(stroke
				(width 0.1)
				(type default)
			)
			(layer "F.Fab")
		)
		(fp_line
			(start 0.120396 0.3048)
			(end 0.120396 0.2794)
			(stroke
				(width 0.1)
				(type default)
			)
			(layer "F.Fab")
		)
		(fp_line
			(start 0.67945 0.3048)
			(end 0.120396 0.3048)
			(stroke
				(width 0.1)
				(type default)
			)
			(layer "F.Fab")
		)
		(fp_line
			(start -0.12065 0.2794)
			(end -0.12065 0.3048)
			(stroke
				(width 0.1)
				(type default)
			)
			(layer "F.Fab")
		)
		(fp_line
			(start 0.120396 0.2794)
			(end -0.12065 0.2794)
			(stroke
				(width 0.1)
				(type default)
			)
			(layer "F.Fab")
		)
		(fp_line
			(start -0.12065 -0.2794)
			(end 0.12065 -0.2794)
			(stroke
				(width 0.1)
				(type default)
			)
			(layer "F.Fab")
		)
		(fp_line
			(start 0.12065 -0.2794)
			(end 0.12065 -0.3048)
			(stroke
				(width 0.1)
				(type default)
			)
			(layer "F.Fab")
		)
		(fp_line
			(start 0.12065 -0.3048)
			(end 0.67945 -0.3048)
			(stroke
				(width 0.1)
				(type default)
			)
			(layer "F.Fab")
		)
		(fp_line
			(start 0.67945 -0.3048)
			(end 0.67945 0.3048)
			(stroke
				(width 0.1)
				(type default)
			)
			(layer "F.Fab")
		)
		(fp_line
			(start -0.67945 -0.305054)
			(end -0.12065 -0.305054)
			(stroke
				(width 0.1)
				(type default)
			)
			(layer "F.Fab")
		)
		(fp_line
			(start -0.12065 -0.305054)
			(end -0.12065 -0.2794)
			(stroke
				(width 0.1)
				(type default)
			)
			(layer "F.Fab")
		)
		(pad "1" smd circle
			(at -0.40005 0 270)
			(size 0 0)
			(layers "F.Cu" "F.Mask" "F.Paste")
			(net "FM_CPU0_PROCHOT_R_N")
		)
		(pad "2" smd circle
			(at 0.40005 0 270)
			(size 0 0)
			(layers "F.Cu" "F.Mask" "F.Paste")
			(net "CPU0_PROCHOT_N")
		)
	)
	(footprint ""
		(layer "F.Cu")
		(at 320.921888 -22.571456 90)
		(property "Reference" "R130"
			(at 0 0 90)
			(layer "F.SilkS")
			(hide yes)
			(effects
				(font
					(size 1.27 1.27)
				)
			)
		)
		(property "Value" ""
			(at 0 0 90)
			(layer "F.Fab")
			(effects
				(font
					(size 1.27 1.27)
				)
			)
		)
		(duplicate_pad_numbers_are_jumpers no)
		(fp_line
			(start 0.7874 -0.4064)
			(end 0.7874 0.4064)
			(stroke
				(width 0.1524)
				(type default)
			)
			(layer "F.SilkS")
		)
		(fp_line
			(start -0.7874 -0.4064)
			(end 0.7874 -0.4064)
			(stroke
				(width 0.1524)
				(type default)
			)
			(layer "F.SilkS")
		)
		(fp_line
			(start 0.7874 0.4064)
			(end -0.7874 0.4064)
			(stroke
				(width 0.1524)
				(type default)
			)
			(layer "F.SilkS")
		)
		(fp_line
			(start -0.7874 0.4064)
			(end -0.7874 -0.4064)
			(stroke
				(width 0.1524)
				(type default)
			)
			(layer "F.SilkS")
		)
		(fp_line
			(start -0.12065 -0.305054)
			(end -0.12065 -0.2794)
			(stroke
				(width 0.1)
				(type default)
			)
			(layer "F.Fab")
		)
		(fp_line
			(start -0.67945 -0.305054)
			(end -0.12065 -0.305054)
			(stroke
				(width 0.1)
				(type default)
			)
			(layer "F.Fab")
		)
		(fp_line
			(start 0.67945 -0.3048)
			(end 0.67945 0.3048)
			(stroke
				(width 0.1)
				(type default)
			)
			(layer "F.Fab")
		)
		(fp_line
			(start 0.12065 -0.3048)
			(end 0.67945 -0.3048)
			(stroke
				(width 0.1)
				(type default)
			)
			(layer "F.Fab")
		)
		(fp_line
			(start 0.12065 -0.2794)
			(end 0.12065 -0.3048)
			(stroke
				(width 0.1)
				(type default)
			)
			(layer "F.Fab")
		)
		(fp_line
			(start -0.12065 -0.2794)
			(end 0.12065 -0.2794)
			(stroke
				(width 0.1)
				(type default)
			)
			(layer "F.Fab")
		)
		(fp_line
			(start 0.120396 0.2794)
			(end -0.12065 0.2794)
			(stroke
				(width 0.1)
				(type default)
			)
			(layer "F.Fab")
		)
		(fp_line
			(start -0.12065 0.2794)
			(end -0.12065 0.3048)
			(stroke
				(width 0.1)
				(type default)
			)
			(layer "F.Fab")
		)
		(fp_line
			(start 0.67945 0.3048)
			(end 0.120396 0.3048)
			(stroke
				(width 0.1)
				(type default)
			)
			(layer "F.Fab")
		)
		(fp_line
			(start 0.120396 0.3048)
			(end 0.120396 0.2794)
			(stroke
				(width 0.1)
				(type default)
			)
			(layer "F.Fab")
		)
		(fp_line
			(start -0.12065 0.3048)
			(end -0.67945 0.3048)
			(stroke
				(width 0.1)
				(type default)
			)
			(layer "F.Fab")
		)
		(fp_line
			(start -0.67945 0.3048)
			(end -0.67945 -0.305054)
			(stroke
				(width 0.1)
				(type default)
			)
			(layer "F.Fab")
		)
		(pad "1" smd circle
			(at -0.40005 0 90)
			(size 0 0)
			(layers "F.Cu" "F.Mask" "F.Paste")
			(net "UART_VCC_J8")
		)
		(pad "2" smd circle
			(at 0.40005 0 90)
			(size 0 0)
			(layers "F.Cu" "F.Mask" "F.Paste")
			(net "P5V_AUX")
		)
	)
	(footprint ""
		(layer "F.Cu")
		(at 330.523342 -393.86256)
		(property "Reference" "R1027"
			(at 0 0 0)
			(layer "F.SilkS")
			(hide yes)
			(effects
				(font
					(size 1.27 1.27)
				)
			)
		)
		(property "Value" ""
			(at 0 0 0)
			(layer "F.Fab")
			(effects
				(font
					(size 1.27 1.27)
				)
			)
		)
		(duplicate_pad_numbers_are_jumpers no)
		(fp_line
			(start -0.32512 -0.175006)
			(end 0.32512 -0.175006)
			(stroke
				(width 0.1)
				(type default)
			)
			(layer "F.Fab")
		)
		(fp_line
			(start -0.32512 0.175006)
			(end -0.32512 -0.175006)
			(stroke
				(width 0.1)
				(type default)
			)
			(layer "F.Fab")
		)
		(fp_line
			(start 0.32512 -0.175006)
			(end 0.32512 0.175006)
			(stroke
				(width 0.1)
				(type default)
			)
			(layer "F.Fab")
		)
		(fp_line
			(start 0.32512 0.175006)
			(end -0.32512 0.175006)
			(stroke
				(width 0.1)
				(type default)
			)
			(layer "F.Fab")
		)
		(pad "1" smd rect
			(at -0.2667 0)
			(size 0.3048 0.381)
			(layers "F.Cu" "F.Mask" "F.Paste")
			(net "P1V8_CPU0_RT_1D")
		)
		(pad "2" smd rect
			(at 0.2667 0 180)
			(size 0.3048 0.381)
			(layers "F.Cu" "F.Mask" "F.Paste")
			(net "GPIO2_RT_CPU0_P1")
		)
	)
)
